(kicad_pcb
	(version 20260206)
	(generator "pcbnew")
	(generator_version "10.0")
	(general
		(thickness 1.6)
		(legacy_teardrops no)
	)
	(paper "A4")
	(title_block
		(title "Bryce Canyon_SCC_16316-1_OCP.brd")
		(comment 1 "Bryce Canyon / footprints 1010-1018 of 1561")
	)
	(layers
		(0 "F.Cu" signal "TOP")
		(4 "In1.Cu" signal "L2GND")
		(6 "In2.Cu" signal "L3")
		(8 "In3.Cu" signal "L4VCC")
		(10 "In4.Cu" signal "L5VCC")
		(12 "In5.Cu" signal "L6")
		(14 "In6.Cu" signal "L7GND")
		(2 "B.Cu" signal "BOTTOM")
		(9 "F.Adhes" user "F.Adhesive")
		(11 "B.Adhes" user "B.Adhesive")
		(13 "F.Paste" user "Package Geometry/Pastemask Top")
		(15 "B.Paste" user "Package Geometry/Pastemask Bottom")
		(5 "F.SilkS" user "Ref Des/Silkscreen Top")
		(7 "B.SilkS" user "Ref Des/Silkscreen Bottom")
		(1 "F.Mask" user "Board Geometry/Soldermask Top")
		(3 "B.Mask" user "Board Geometry/Soldermask Bottom")
		(17 "Dwgs.User" user "User.Drawings")
		(19 "Cmts.User" user "User.Comments")
		(21 "Eco1.User" user "User.Eco1")
		(23 "Eco2.User" user "User.Eco2")
		(25 "Edge.Cuts" user "Board Geometry/Outline")
		(27 "Margin" user)
		(31 "F.CrtYd" user "Package Geometry/Place Bound Top")
		(29 "B.CrtYd" user "Package Geometry/Place Bound Bottom")
		(35 "F.Fab" user "Ref Des/Assembly Top")
		(33 "B.Fab" user "Ref Des/Assembly Bottom")
	)
	(footprint ""
		(layer "B.Cu")
		(at 181.26964 -21.27504 90)
		(property "Reference" "C325"
			(at 0 0 90)
			(layer "B.SilkS")
			(hide yes)
			(effects
				(font
					(size 1.27 1.27)
				)
				(justify mirror)
			)
		)
		(property "Value" "SCD22U10V1KX-GP"
			(at 2.8321 -1.7399 90)
			(unlocked yes)
			(layer "B.Fab")
			(hide yes)
			(effects
				(font
					(size 1.016 1.016)
					(thickness 0.1524)
				)
				(justify mirror)
			)
		)
		(property "Device Type" "C0201H13"
			(at 2.8321 -3.2639 90)
			(unlocked yes)
			(layer "B.Fab")
			(hide yes)
			(effects
				(font
					(size 1.016 1.016)
					(thickness 0.1524)
				)
				(justify mirror)
			)
		)
		(duplicate_pad_numbers_are_jumpers no)
		(fp_rect
			(start 0.2794 0.6477)
			(end -0.2794 -0.6477)
			(stroke
				(width 0)
				(type default)
			)
			(fill no)
			(layer "B.CrtYd")
		)
		(fp_rect
			(start 0.2794 0.6477)
			(end -0.2794 -0.6477)
			(stroke
				(width 0)
				(type default)
			)
			(fill no)
			(layer "B.Fab")
		)
		(pad "1" smd custom
			(at 0 -0.2794 270)
			(size 0.0762 0.0762)
			(layers "B.Cu" "B.Mask" "B.Paste")
			(net "PCIE_SCC_TO_COMP_C_7_DP")
			(options
				(clearance outline)
				(anchor circle)
			)
			(primitives
				(gr_poly
					(pts
						(arc
							(start 0.1524 0.127)
							(mid 0.137521 0.162921)
							(end 0.1016 0.1778)
						)
						(arc
							(start -0.1016 0.1778)
							(mid -0.137521 0.162921)
							(end -0.1524 0.127)
						)
						(arc
							(start -0.1524 -0.127)
							(mid -0.137521 -0.162921)
							(end -0.1016 -0.1778)
						)
						(arc
							(start 0.1016 -0.1778)
							(mid 0.137521 -0.162921)
							(end 0.1524 -0.127)
						)
					)
					(width 0)
					(fill yes)
				)
			)
		)
		(pad "2" smd custom
			(at 0 0.2794 270)
			(size 0.0762 0.0762)
			(layers "B.Cu" "B.Mask" "B.Paste")
			(net "PCIE_SCC_TO_COMP_7_DP")
			(options
				(clearance outline)
				(anchor circle)
			)
			(primitives
				(gr_poly
					(pts
						(arc
							(start 0.1524 0.127)
							(mid 0.137521 0.162921)
							(end 0.1016 0.1778)
						)
						(arc
							(start -0.1016 0.1778)
							(mid -0.137521 0.162921)
							(end -0.1524 0.127)
						)
						(arc
							(start -0.1524 -0.127)
							(mid -0.137521 -0.162921)
							(end -0.1016 -0.1778)
						)
						(arc
							(start 0.1016 -0.1778)
							(mid 0.137521 -0.162921)
							(end 0.1524 -0.127)
						)
					)
					(width 0)
					(fill yes)
				)
			)
		)
	)
	(footprint ""
		(layer "B.Cu")
		(at 129.397252 -56.71566 90)
		(property "Reference" "C232"
			(at 0 0 90)
			(layer "B.SilkS")
			(hide yes)
			(effects
				(font
					(size 1.27 1.27)
				)
				(justify mirror)
			)
		)
		(property "Value" "SCD1U6D3V1KX-GP"
			(at 2.8321 -1.7399 90)
			(unlocked yes)
			(layer "B.Fab")
			(hide yes)
			(effects
				(font
					(size 1.016 1.016)
					(thickness 0.1524)
				)
				(justify mirror)
			)
		)
		(property "Device Type" "C0201H13"
			(at 2.8321 -3.2639 90)
			(unlocked yes)
			(layer "B.Fab")
			(hide yes)
			(effects
				(font
					(size 1.016 1.016)
					(thickness 0.1524)
				)
				(justify mirror)
			)
		)
		(duplicate_pad_numbers_are_jumpers no)
		(fp_rect
			(start 0.2794 0.6477)
			(end -0.2794 -0.6477)
			(stroke
				(width 0)
				(type default)
			)
			(fill no)
			(layer "B.CrtYd")
		)
		(fp_rect
			(start 0.2794 0.6477)
			(end -0.2794 -0.6477)
			(stroke
				(width 0)
				(type default)
			)
			(fill no)
			(layer "B.Fab")
		)
		(pad "1" smd custom
			(at 0 -0.2794 270)
			(size 0.0762 0.0762)
			(layers "B.Cu" "B.Mask" "B.Paste")
			(net "GB_VDDA")
			(options
				(clearance outline)
				(anchor circle)
			)
			(primitives
				(gr_poly
					(pts
						(arc
							(start 0.1524 0.127)
							(mid 0.137521 0.162921)
							(end 0.1016 0.1778)
						)
						(arc
							(start -0.1016 0.1778)
							(mid -0.137521 0.162921)
							(end -0.1524 0.127)
						)
						(arc
							(start -0.1524 -0.127)
							(mid -0.137521 -0.162921)
							(end -0.1016 -0.1778)
						)
						(arc
							(start 0.1016 -0.1778)
							(mid 0.137521 -0.162921)
							(end 0.1524 -0.127)
						)
					)
					(width 0)
					(fill yes)
				)
			)
		)
		(pad "2" smd custom
			(at 0 0.2794 270)
			(size 0.0762 0.0762)
			(layers "B.Cu" "B.Mask" "B.Paste")
			(net "GND")
			(options
				(clearance outline)
				(anchor circle)
			)
			(primitives
				(gr_poly
					(pts
						(arc
							(start 0.1524 0.127)
							(mid 0.137521 0.162921)
							(end 0.1016 0.1778)
						)
						(arc
							(start -0.1016 0.1778)
							(mid -0.137521 0.162921)
							(end -0.1524 0.127)
						)
						(arc
							(start -0.1524 -0.127)
							(mid -0.137521 -0.162921)
							(end -0.1016 -0.1778)
						)
						(arc
							(start 0.1016 -0.1778)
							(mid 0.137521 -0.162921)
							(end 0.1524 -0.127)
						)
					)
					(width 0)
					(fill yes)
				)
			)
		)
	)
	(footprint ""
		(layer "B.Cu")
		(at 106.299 -64.516 -90)
		(property "Reference" "C203"
			(at 0 0 90)
			(layer "B.SilkS")
			(hide yes)
			(effects
				(font
					(size 1.27 1.27)
				)
				(justify mirror)
			)
		)
		(property "Value" "SCD1U6D3V1KX-GP"
			(at 2.8321 -1.7399 270)
			(unlocked yes)
			(layer "B.Fab")
			(hide yes)
			(effects
				(font
					(size 1.016 1.016)
					(thickness 0.1524)
				)
				(justify mirror)
			)
		)
		(property "Device Type" "C0201H13"
			(at 2.8321 -3.2639 270)
			(unlocked yes)
			(layer "B.Fab")
			(hide yes)
			(effects
				(font
					(size 1.016 1.016)
					(thickness 0.1524)
				)
				(justify mirror)
			)
		)
		(duplicate_pad_numbers_are_jumpers no)
		(fp_rect
			(start 0.2794 0.6477)
			(end -0.2794 -0.6477)
			(stroke
				(width 0)
				(type default)
			)
			(fill no)
			(layer "B.CrtYd")
		)
		(fp_rect
			(start 0.2794 0.6477)
			(end -0.2794 -0.6477)
			(stroke
				(width 0)
				(type default)
			)
			(fill no)
			(layer "B.Fab")
		)
		(pad "1" smd custom
			(at 0 -0.2794 90)
			(size 0.0762 0.0762)
			(layers "B.Cu" "B.Mask" "B.Paste")
			(net "PLLDDR_VDDA18")
			(options
				(clearance outline)
				(anchor circle)
			)
			(primitives
				(gr_poly
					(pts
						(arc
							(start 0.1524 0.127)
							(mid 0.137521 0.162921)
							(end 0.1016 0.1778)
						)
						(arc
							(start -0.1016 0.1778)
							(mid -0.137521 0.162921)
							(end -0.1524 0.127)
						)
						(arc
							(start -0.1524 -0.127)
							(mid -0.137521 -0.162921)
							(end -0.1016 -0.1778)
						)
						(arc
							(start 0.1016 -0.1778)
							(mid 0.137521 -0.162921)
							(end 0.1524 -0.127)
						)
					)
					(width 0)
					(fill yes)
				)
			)
		)
		(pad "2" smd custom
			(at 0 0.2794 90)
			(size 0.0762 0.0762)
			(layers "B.Cu" "B.Mask" "B.Paste")
			(net "GND")
			(options
				(clearance outline)
				(anchor circle)
			)
			(primitives
				(gr_poly
					(pts
						(arc
							(start 0.1524 0.127)
							(mid 0.137521 0.162921)
							(end 0.1016 0.1778)
						)
						(arc
							(start -0.1016 0.1778)
							(mid -0.137521 0.162921)
							(end -0.1524 0.127)
						)
						(arc
							(start -0.1524 -0.127)
							(mid -0.137521 -0.162921)
							(end -0.1016 -0.1778)
						)
						(arc
							(start 0.1016 -0.1778)
							(mid 0.137521 -0.162921)
							(end 0.1524 -0.127)
						)
					)
					(width 0)
					(fill yes)
				)
			)
		)
	)
	(footprint ""
		(layer "B.Cu")
		(at 128.7018 -85.3948)
		(property "Reference" "TP159"
			(at 0 0 0)
			(layer "B.SilkS")
			(hide yes)
			(effects
				(font
					(size 1.27 1.27)
				)
				(justify mirror)
			)
		)
		(property "Value" "TPAD28-2-GP"
			(at 0.0127 -1.6637 0)
			(unlocked yes)
			(layer "B.Fab")
			(hide yes)
			(effects
				(font
					(size 1.016 1.016)
					(thickness 0.1524)
				)
				(justify mirror)
			)
		)
		(property "Device Type" "TPAD28"
			(at 0.0127 -3.1877 0)
			(unlocked yes)
			(layer "B.Fab")
			(hide yes)
			(effects
				(font
					(size 1.016 1.016)
					(thickness 0.1524)
				)
				(justify mirror)
			)
		)
		(duplicate_pad_numbers_are_jumpers no)
		(fp_poly
			(pts
				(arc
					(start 0.3556 0)
					(mid -0.3556 0)
					(end 0.3556 0)
				)
			)
			(stroke
				(width 0)
				(type default)
			)
			(fill no)
			(layer "B.CrtYd")
		)
		(fp_poly
			(pts
				(arc
					(start 0.6096 0)
					(mid -0.6096 0)
					(end 0.6096 0)
				)
			)
			(stroke
				(width 0)
				(type default)
			)
			(fill no)
			(layer "B.Fab")
		)
		(pad "1" smd circle
			(at 0 0 180)
			(size 0.7112 0.7112)
			(layers "B.Cu" "B.Mask" "B.Paste")
			(net "ICE_TMS")
		)
	)
	(footprint ""
		(layer "B.Cu")
		(at 168.963848 -49.70907 90)
		(property "Reference" "C494"
			(at 0 0 90)
			(layer "B.SilkS")
			(hide yes)
			(effects
				(font
					(size 1.27 1.27)
				)
				(justify mirror)
			)
		)
		(property "Value" "SC1KP50V2KX-1GP"
			(at -1.1811 -2.7051 90)
			(unlocked yes)
			(layer "B.Fab")
			(hide yes)
			(effects
				(font
					(size 1.016 1.016)
					(thickness 0.1524)
				)
				(justify mirror)
			)
		)
		(property "Device Type" "C402H22"
			(at -1.1811 -4.2291 90)
			(unlocked yes)
			(layer "B.Fab")
			(hide yes)
			(effects
				(font
					(size 1.016 1.016)
					(thickness 0.1524)
				)
				(justify mirror)
			)
		)
		(duplicate_pad_numbers_are_jumpers no)
		(fp_rect
			(start 0.4318 0.9525)
			(end -0.4318 -0.9525)
			(stroke
				(width 0)
				(type default)
			)
			(fill no)
			(layer "B.CrtYd")
		)
		(fp_rect
			(start 0.4318 0.9525)
			(end -0.4318 -0.9525)
			(stroke
				(width 0)
				(type default)
			)
			(fill no)
			(layer "B.Fab")
		)
		(pad "1" smd custom
			(at 0 -0.4445 270)
			(size 0.1524 0.1524)
			(layers "B.Cu" "B.Mask" "B.Paste")
			(net "P1V8_C")
			(options
				(clearance outline)
				(anchor circle)
			)
			(primitives
				(gr_poly
					(pts
						(arc
							(start 0.3048 0.2032)
							(mid 0.275042 0.275042)
							(end 0.2032 0.3048)
						)
						(arc
							(start -0.2032 0.3048)
							(mid -0.275042 0.275042)
							(end -0.3048 0.2032)
						)
						(arc
							(start -0.3048 -0.2032)
							(mid -0.275042 -0.275042)
							(end -0.2032 -0.3048)
						)
						(arc
							(start 0.2032 -0.3048)
							(mid 0.275042 -0.275042)
							(end 0.3048 -0.2032)
						)
					)
					(width 0)
					(fill yes)
				)
			)
		)
		(pad "2" smd custom
			(at 0 0.4445 270)
			(size 0.1524 0.1524)
			(layers "B.Cu" "B.Mask" "B.Paste")
			(net "GND")
			(options
				(clearance outline)
				(anchor circle)
			)
			(primitives
				(gr_poly
					(pts
						(arc
							(start 0.3048 0.2032)
							(mid 0.275042 0.275042)
							(end 0.2032 0.3048)
						)
						(arc
							(start -0.2032 0.3048)
							(mid -0.275042 0.275042)
							(end -0.3048 0.2032)
						)
						(arc
							(start -0.3048 -0.2032)
							(mid -0.275042 -0.275042)
							(end -0.2032 -0.3048)
						)
						(arc
							(start 0.2032 -0.3048)
							(mid 0.275042 -0.275042)
							(end 0.3048 -0.2032)
						)
					)
					(width 0)
					(fill yes)
				)
			)
		)
	)
	(footprint ""
		(layer "B.Cu")
		(at 96.497394 -53.744368 90)
		(property "Reference" "C93"
			(at 0 0 90)
			(layer "B.SilkS")
			(hide yes)
			(effects
				(font
					(size 1.27 1.27)
				)
				(justify mirror)
			)
		)
		(property "Value" "SCD01U16V1KX-GP"
			(at 2.8321 -1.7399 90)
			(unlocked yes)
			(layer "B.Fab")
			(hide yes)
			(effects
				(font
					(size 1.016 1.016)
					(thickness 0.1524)
				)
				(justify mirror)
			)
		)
		(property "Device Type" "C0201H13"
			(at 2.8321 -3.2639 90)
			(unlocked yes)
			(layer "B.Fab")
			(hide yes)
			(effects
				(font
					(size 1.016 1.016)
					(thickness 0.1524)
				)
				(justify mirror)
			)
		)
		(duplicate_pad_numbers_are_jumpers no)
		(fp_rect
			(start 0.2794 0.6477)
			(end -0.2794 -0.6477)
			(stroke
				(width 0)
				(type default)
			)
			(fill no)
			(layer "B.CrtYd")
		)
		(fp_rect
			(start 0.2794 0.6477)
			(end -0.2794 -0.6477)
			(stroke
				(width 0)
				(type default)
			)
			(fill no)
			(layer "B.Fab")
		)
		(pad "1" smd custom
			(at 0 -0.2794 270)
			(size 0.0762 0.0762)
			(layers "B.Cu" "B.Mask" "B.Paste")
			(net "PHY_DPB_TO_SCC_13_DN")
			(options
				(clearance outline)
				(anchor circle)
			)
			(primitives
				(gr_poly
					(pts
						(arc
							(start 0.1524 0.127)
							(mid 0.137521 0.162921)
							(end 0.1016 0.1778)
						)
						(arc
							(start -0.1016 0.1778)
							(mid -0.137521 0.162921)
							(end -0.1524 0.127)
						)
						(arc
							(start -0.1524 -0.127)
							(mid -0.137521 -0.162921)
							(end -0.1016 -0.1778)
						)
						(arc
							(start 0.1016 -0.1778)
							(mid 0.137521 -0.162921)
							(end 0.1524 -0.127)
						)
					)
					(width 0)
					(fill yes)
				)
			)
		)
		(pad "2" smd custom
			(at 0 0.2794 270)
			(size 0.0762 0.0762)
			(layers "B.Cu" "B.Mask" "B.Paste")
			(net "PHY_DPB_TO_SCC_C_13_DN")
			(options
				(clearance outline)
				(anchor circle)
			)
			(primitives
				(gr_poly
					(pts
						(arc
							(start 0.1524 0.127)
							(mid 0.137521 0.162921)
							(end 0.1016 0.1778)
						)
						(arc
							(start -0.1016 0.1778)
							(mid -0.137521 0.162921)
							(end -0.1524 0.127)
						)
						(arc
							(start -0.1524 -0.127)
							(mid -0.137521 -0.162921)
							(end -0.1016 -0.1778)
						)
						(arc
							(start 0.1016 -0.1778)
							(mid 0.137521 -0.162921)
							(end 0.1524 -0.127)
						)
					)
					(width 0)
					(fill yes)
				)
			)
		)
	)
	(footprint ""
		(layer "B.Cu")
		(at 173.629828 -49.65573 -90)
		(property "Reference" "C466"
			(at 0 0 90)
			(layer "B.SilkS")
			(hide yes)
			(effects
				(font
					(size 1.27 1.27)
				)
				(justify mirror)
			)
		)
		(property "Value" "SCD1U6D3V1KX-GP"
			(at 2.8321 -1.7399 270)
			(unlocked yes)
			(layer "B.Fab")
			(hide yes)
			(effects
				(font
					(size 1.016 1.016)
					(thickness 0.1524)
				)
				(justify mirror)
			)
		)
		(property "Device Type" "C0201H13"
			(at 2.8321 -3.2639 270)
			(unlocked yes)
			(layer "B.Fab")
			(hide yes)
			(effects
				(font
					(size 1.016 1.016)
					(thickness 0.1524)
				)
				(justify mirror)
			)
		)
		(duplicate_pad_numbers_are_jumpers no)
		(fp_rect
			(start 0.2794 0.6477)
			(end -0.2794 -0.6477)
			(stroke
				(width 0)
				(type default)
			)
			(fill no)
			(layer "B.CrtYd")
		)
		(fp_rect
			(start 0.2794 0.6477)
			(end -0.2794 -0.6477)
			(stroke
				(width 0)
				(type default)
			)
			(fill no)
			(layer "B.Fab")
		)
		(pad "1" smd custom
			(at 0 -0.2794 90)
			(size 0.0762 0.0762)
			(layers "B.Cu" "B.Mask" "B.Paste")
			(net "P1V8_C")
			(options
				(clearance outline)
				(anchor circle)
			)
			(primitives
				(gr_poly
					(pts
						(arc
							(start 0.1524 0.127)
							(mid 0.137521 0.162921)
							(end 0.1016 0.1778)
						)
						(arc
							(start -0.1016 0.1778)
							(mid -0.137521 0.162921)
							(end -0.1524 0.127)
						)
						(arc
							(start -0.1524 -0.127)
							(mid -0.137521 -0.162921)
							(end -0.1016 -0.1778)
						)
						(arc
							(start 0.1016 -0.1778)
							(mid 0.137521 -0.162921)
							(end 0.1524 -0.127)
						)
					)
					(width 0)
					(fill yes)
				)
			)
		)
		(pad "2" smd custom
			(at 0 0.2794 90)
			(size 0.0762 0.0762)
			(layers "B.Cu" "B.Mask" "B.Paste")
			(net "GND")
			(options
				(clearance outline)
				(anchor circle)
			)
			(primitives
				(gr_poly
					(pts
						(arc
							(start 0.1524 0.127)
							(mid 0.137521 0.162921)
							(end 0.1016 0.1778)
						)
						(arc
							(start -0.1016 0.1778)
							(mid -0.137521 0.162921)
							(end -0.1524 0.127)
						)
						(arc
							(start -0.1524 -0.127)
							(mid -0.137521 -0.162921)
							(end -0.1016 -0.1778)
						)
						(arc
							(start 0.1016 -0.1778)
							(mid 0.137521 -0.162921)
							(end 0.1524 -0.127)
						)
					)
					(width 0)
					(fill yes)
				)
			)
		)
	)
	(footprint ""
		(layer "B.Cu")
		(at 182.913782 -49.633632 -90)
		(property "Reference" "C501"
			(at 0 0 90)
			(layer "B.SilkS")
			(hide yes)
			(effects
				(font
					(size 1.27 1.27)
				)
				(justify mirror)
			)
		)
		(property "Value" "SC1KP50V2KX-1GP"
			(at -1.1811 -2.7051 270)
			(unlocked yes)
			(layer "B.Fab")
			(hide yes)
			(effects
				(font
					(size 1.016 1.016)
					(thickness 0.1524)
				)
				(justify mirror)
			)
		)
		(property "Device Type" "C402H22"
			(at -1.1811 -4.2291 270)
			(unlocked yes)
			(layer "B.Fab")
			(hide yes)
			(effects
				(font
					(size 1.016 1.016)
					(thickness 0.1524)
				)
				(justify mirror)
			)
		)
		(duplicate_pad_numbers_are_jumpers no)
		(fp_rect
			(start 0.4318 0.9525)
			(end -0.4318 -0.9525)
			(stroke
				(width 0)
				(type default)
			)
			(fill no)
			(layer "B.CrtYd")
		)
		(fp_rect
			(start 0.4318 0.9525)
			(end -0.4318 -0.9525)
			(stroke
				(width 0)
				(type default)
			)
			(fill no)
			(layer "B.Fab")
		)
		(pad "1" smd custom
			(at 0 -0.4445 90)
			(size 0.1524 0.1524)
			(layers "B.Cu" "B.Mask" "B.Paste")
			(net "P1V8_C")
			(options
				(clearance outline)
				(anchor circle)
			)
			(primitives
				(gr_poly
					(pts
						(arc
							(start 0.3048 0.2032)
							(mid 0.275042 0.275042)
							(end 0.2032 0.3048)
						)
						(arc
							(start -0.2032 0.3048)
							(mid -0.275042 0.275042)
							(end -0.3048 0.2032)
						)
						(arc
							(start -0.3048 -0.2032)
							(mid -0.275042 -0.275042)
							(end -0.2032 -0.3048)
						)
						(arc
							(start 0.2032 -0.3048)
							(mid 0.275042 -0.275042)
							(end 0.3048 -0.2032)
						)
					)
					(width 0)
					(fill yes)
				)
			)
		)
		(pad "2" smd custom
			(at 0 0.4445 90)
			(size 0.1524 0.1524)
			(layers "B.Cu" "B.Mask" "B.Paste")
			(net "GND")
			(options
				(clearance outline)
				(anchor circle)
			)
			(primitives
				(gr_poly
					(pts
						(arc
							(start 0.3048 0.2032)
							(mid 0.275042 0.275042)
							(end 0.2032 0.3048)
						)
						(arc
							(start -0.2032 0.3048)
							(mid -0.275042 0.275042)
							(end -0.3048 0.2032)
						)
						(arc
							(start -0.3048 -0.2032)
							(mid -0.275042 -0.275042)
							(end -0.2032 -0.3048)
						)
						(arc
							(start 0.2032 -0.3048)
							(mid 0.275042 -0.275042)
							(end 0.3048 -0.2032)
						)
					)
					(width 0)
					(fill yes)
				)
			)
		)
	)
	(footprint ""
		(layer "B.Cu")
		(at 178.7144 -28.0924)
		(property "Reference" "TP116"
			(at 0 0 0)
			(layer "B.SilkS")
			(hide yes)
			(effects
				(font
					(size 1.27 1.27)
				)
				(justify mirror)
			)
		)
		(property "Value" "TPAD28-2-GP"
			(at 0.0127 -1.6637 0)
			(unlocked yes)
			(layer "B.Fab")
			(hide yes)
			(effects
				(font
					(size 1.016 1.016)
					(thickness 0.1524)
				)
				(justify mirror)
			)
		)
		(property "Device Type" "TPAD28"
			(at 0.0127 -3.1877 0)
			(unlocked yes)
			(layer "B.Fab")
			(hide yes)
			(effects
				(font
					(size 1.016 1.016)
					(thickness 0.1524)
				)
				(justify mirror)
			)
		)
		(duplicate_pad_numbers_are_jumpers no)
		(fp_poly
			(pts
				(arc
					(start 0.3556 0)
					(mid -0.3556 0)
					(end 0.3556 0)
				)
			)
			(stroke
				(width 0)
				(type default)
			)
			(fill no)
			(layer "B.CrtYd")
		)
		(fp_poly
			(pts
				(arc
					(start 0.6096 0)
					(mid -0.6096 0)
					(end 0.6096 0)
				)
			)
			(stroke
				(width 0)
				(type default)
			)
			(fill no)
			(layer "B.Fab")
		)
		(pad "1" smd circle
			(at 0 0 180)
			(size 0.7112 0.7112)
			(layers "B.Cu" "B.Mask" "B.Paste")
			(net "IOC_UART_1_TX")
		)
	)
)
